FILE_TYPE=LIBRARY_PARTS;
TIME=' Compilation on Wed Jan 31 17:00:00 2001';
PRIMITIVE 'Q_CAPP';
PIN
 'A':
   PIN_NUMBER='(1)';
   PIN_TYPE='UNSPEC';
   NO_LOAD_CHECK='BOTH';
   NO_IO_CHECK='BOTH';
 'B':
   PIN_NUMBER='(2)';
   PIN_TYPE='UNSPEC';
   NO_LOAD_CHECK='BOTH';
   NO_IO_CHECK='BOTH';
END_PIN;
BODY
 PART_NAME='Q_CAPP';
 PHYS_DES_PREFIX='C';
END_BODY;
END_PRIMITIVE;
END.

